# T6G (Grand Teton) — schematic netlist excerpt (pin names and nets, part order shuffled) for the footprints in the layout excerpt that follows; sources: Cadence DE-HDL packaged netlist, KiCad conversion of 04192023_DAF0TMB3IC0_F0TG_MB_C_brd_V02_OCP.brd

C928  Q_CAP_DIFFBUS  DIFF BUS_0.22UF 6.3V 20% X6S  pkg C0201  page 63 : \1\ = P5E_CPU0_P0_TX_C_DN<2> ; \2\ = P5E_CPU0_P0_TX_DN<2>

J79  PICOPROBE_BXA  DELTA-L 4.0 EMPTY  pkg TRIANG_LAUNCH_3PXB  page 229
  \1_p\  = DELTA_L_85_10INCH_IN3_DP
  \2_n\  = DELTA_L_85_10INCH_IN3_DN
  \3_g\  = DELTA_L_GND_1

(kicad_pcb
	(version 20260206)
	(generator "pcbnew")
	(generator_version "10.0")
	(general
		(thickness 1.6)
		(legacy_teardrops no)
	)
	(paper "A4")
	(title_block
		(title "04192023_DAF0TMB3IC0_F0TG_MB_C_brd_V02_OCP.brd")
		(comment 1 "Grand Teton / footprints 2257-2258 of 8354")
	)
	(layers
		(0 "F.Cu" signal "TOP")
		(4 "In1.Cu" signal "GND")
		(6 "In2.Cu" signal "IN1")
		(8 "In3.Cu" signal "GND1")
		(10 "In4.Cu" signal "IN2")
		(12 "In5.Cu" signal "GND2")
		(14 "In6.Cu" signal "IN3")
		(16 "In7.Cu" signal "GND3")
		(18 "In8.Cu" signal "VCC")
		(20 "In9.Cu" signal "VCC1")
		(22 "In10.Cu" signal "GND4")
		(24 "In11.Cu" signal "IN4")
		(26 "In12.Cu" signal "GND5")
		(28 "In13.Cu" signal "IN5")
		(30 "In14.Cu" signal "GND6")
		(32 "In15.Cu" signal "IN6")
		(34 "In16.Cu" signal "GND7")
		(2 "B.Cu" signal "BOTTOM")
		(9 "F.Adhes" user "F.Adhesive")
		(11 "B.Adhes" user "B.Adhesive")
		(13 "F.Paste" user "Package Geometry/Pastemask Top")
		(15 "B.Paste" user "Package Geometry/Pastemask Bottom")
		(5 "F.SilkS" user "Ref Des/Silkscreen Top")
		(7 "B.SilkS" user "Ref Des/Silkscreen Bottom")
		(1 "F.Mask" user "Board Geometry/Soldermask Top")
		(3 "B.Mask" user "Board Geometry/Soldermask Bottom")
		(17 "Dwgs.User" user "User.Drawings")
		(19 "Cmts.User" user "User.Comments")
		(21 "Eco1.User" user "User.Eco1")
		(23 "Eco2.User" user "User.Eco2")
		(25 "Edge.Cuts" user "Board Geometry/Outline")
		(27 "Margin" user)
		(31 "F.CrtYd" user "Package Geometry/Place Bound Top")
		(29 "B.CrtYd" user "Package Geometry/Place Bound Bottom")
		(35 "F.Fab" user "Ref Des/Assembly Top")
		(33 "B.Fab" user "Ref Des/Assembly Bottom")
	)
	(footprint ""
		(layer "F.Cu")
		(at 212.471508 5.082794)
		(property "Reference" "J79"
			(at -4.52374 0.838708 90)
			(unlocked yes)
			(layer "F.SilkS")
			(effects
				(font
					(size 0.7874 0.5842)
					(thickness 0.1524)
				)
				(justify left)
			)
		)
		(property "Value" ""
			(at 0 0 0)
			(layer "F.Fab")
			(effects
				(font
					(size 1.27 1.27)
				)
			)
		)
		(duplicate_pad_numbers_are_jumpers no)
		(fp_line
			(start -1.2192 -2.06756)
			(end 1.2192 -2.06756)
			(stroke
				(width 0.1524)
				(type default)
			)
			(layer "F.SilkS")
		)
		(fp_line
			(start -1.2192 2.06756)
			(end -1.2192 -2.06756)
			(stroke
				(width 0.1524)
				(type default)
			)
			(layer "F.SilkS")
		)
		(fp_line
			(start 1.2192 -2.06756)
			(end 1.2192 2.06756)
			(stroke
				(width 0.1524)
				(type default)
			)
			(layer "F.SilkS")
		)
		(fp_line
			(start 1.2192 2.06756)
			(end -1.2192 2.06756)
			(stroke
				(width 0.1524)
				(type default)
			)
			(layer "F.SilkS")
		)
		(pad "" np_thru_hole circle
			(at -2.8829 -1.27 270)
			(size 1.0414 1.0414)
			(drill 1.0414)
			(layers "*.Cu" "*.Mask")
			(clearance 0.381)
			(thermal_gap 0.381)
		)
		(pad "" np_thru_hole circle
			(at -2.8829 1.27 270)
			(size 1.0414 1.0414)
			(drill 1.0414)
			(layers "*.Cu" "*.Mask")
			(clearance 0.381)
			(thermal_gap 0.381)
		)
		(pad "" np_thru_hole circle
			(at 3.4671 -1.27 270)
			(size 1.0414 1.0414)
			(drill 1.0414)
			(layers "*.Cu" "*.Mask")
			(clearance 0.381)
			(thermal_gap 0.381)
		)
		(pad "" np_thru_hole circle
			(at 3.4671 1.27 270)
			(size 1.0414 1.0414)
			(drill 1.0414)
			(layers "*.Cu" "*.Mask")
			(clearance 0.381)
			(thermal_gap 0.381)
		)
		(pad "1" smd rect
			(at 0.8255 -0.249936 270)
			(size 0.3048 0.508)
			(layers "F.Cu" "F.Mask" "F.Paste")
			(net "DELTA_L_85_10INCH_IN3_DP")
		)
		(pad "2" smd rect
			(at 0.8255 0.249936 270)
			(size 0.3048 0.508)
			(layers "F.Cu" "F.Mask" "F.Paste")
			(net "DELTA_L_85_10INCH_IN3_DN")
		)
		(pad "3" smd circle
			(at 0 0)
			(size 0 0)
			(layers "F.Cu" "F.Mask" "F.Paste")
			(net "DELTA_L_GND_1")
		)
		(zone
			(layer "F.Cu")
			(hatch none 0.5)
			(connect_pads
				(clearance 0)
			)
			(min_thickness 0.25)
			(keepout
				(tracks not_allowed)
				(vias allowed)
				(pads allowed)
				(copperpour not_allowed)
				(footprints allowed)
			)
			(placement
				(enabled no)
				(sheetname "")
			)
			(fill
				(thermal_gap 0.5)
				(thermal_bridge_width 0.5)
				(island_removal_mode 0)
			)
			(polygon
				(pts
					(xy 213.589108 4.534154) (xy 213.589108 4.629658) (xy 212.992208 4.629658) (xy 212.992208 5.036058)
					(xy 213.589108 5.036058) (xy 213.589108 5.12953) (xy 212.992208 5.12953) (xy 212.992208 5.53593)
					(xy 213.589108 5.53593) (xy 213.589108 5.631434) (xy 212.890608 5.631434) (xy 212.890608 4.534154)
				)
			)
		)
		(zone
			(layers "F.Cu" "B.Cu" "In1.Cu" "In2.Cu" "In3.Cu" "In4.Cu" "In5.Cu" "In6.Cu"
				"In7.Cu" "In8.Cu" "In9.Cu" "In10.Cu" "In11.Cu" "In12.Cu" "In13.Cu" "In14.Cu"
				"In15.Cu" "In16.Cu"
			)
			(hatch none 0.5)
			(connect_pads
				(clearance 0)
			)
			(min_thickness 0.25)
			(keepout
				(tracks not_allowed)
				(vias allowed)
				(pads allowed)
				(copperpour not_allowed)
				(footprints allowed)
			)
			(placement
				(enabled no)
				(sheetname "")
			)
			(fill
				(thermal_gap 0.5)
				(thermal_bridge_width 0.5)
				(island_removal_mode 0)
			)
			(polygon
				(pts
					(arc
						(start 210.515708 3.812794)
						(mid 208.661508 3.812794)
						(end 210.515708 3.812794)
					)
				)
			)
		)
		(zone
			(layers "F.Cu" "B.Cu" "In1.Cu" "In2.Cu" "In3.Cu" "In4.Cu" "In5.Cu" "In6.Cu"
				"In7.Cu" "In8.Cu" "In9.Cu" "In10.Cu" "In11.Cu" "In12.Cu" "In13.Cu" "In14.Cu"
				"In15.Cu" "In16.Cu"
			)
			(hatch none 0.5)
			(connect_pads
				(clearance 0)
			)
			(min_thickness 0.25)
			(keepout
				(tracks not_allowed)
				(vias allowed)
				(pads allowed)
				(copperpour not_allowed)
				(footprints allowed)
			)
			(placement
				(enabled no)
				(sheetname "")
			)
			(fill
				(thermal_gap 0.5)
				(thermal_bridge_width 0.5)
				(island_removal_mode 0)
			)
			(polygon
				(pts
					(arc
						(start 210.515708 6.352794)
						(mid 208.661508 6.352794)
						(end 210.515708 6.352794)
					)
				)
			)
		)
		(zone
			(layers "F.Cu" "B.Cu" "In1.Cu" "In2.Cu" "In3.Cu" "In4.Cu" "In5.Cu" "In6.Cu"
				"In7.Cu" "In8.Cu" "In9.Cu" "In10.Cu" "In11.Cu" "In12.Cu" "In13.Cu" "In14.Cu"
				"In15.Cu" "In16.Cu"
			)
			(hatch none 0.5)
			(connect_pads
				(clearance 0)
			)
			(min_thickness 0.25)
			(keepout
				(tracks not_allowed)
				(vias allowed)
				(pads allowed)
				(copperpour not_allowed)
				(footprints allowed)
			)
			(placement
				(enabled no)
				(sheetname "")
			)
			(fill
				(thermal_gap 0.5)
				(thermal_bridge_width 0.5)
				(island_removal_mode 0)
			)
			(polygon
				(pts
					(arc
						(start 216.865708 3.812794)
						(mid 215.011508 3.812794)
						(end 216.865708 3.812794)
					)
				)
			)
		)
		(zone
			(layers "F.Cu" "B.Cu" "In1.Cu" "In2.Cu" "In3.Cu" "In4.Cu" "In5.Cu" "In6.Cu"
				"In7.Cu" "In8.Cu" "In9.Cu" "In10.Cu" "In11.Cu" "In12.Cu" "In13.Cu" "In14.Cu"
				"In15.Cu" "In16.Cu"
			)
			(hatch none 0.5)
			(connect_pads
				(clearance 0)
			)
			(min_thickness 0.25)
			(keepout
				(tracks not_allowed)
				(vias allowed)
				(pads allowed)
				(copperpour not_allowed)
				(footprints allowed)
			)
			(placement
				(enabled no)
				(sheetname "")
			)
			(fill
				(thermal_gap 0.5)
				(thermal_bridge_width 0.5)
				(island_removal_mode 0)
			)
			(polygon
				(pts
					(arc
						(start 216.865708 6.352794)
						(mid 215.011508 6.352794)
						(end 216.865708 6.352794)
					)
				)
			)
		)
	)
	(footprint ""
		(layer "F.Cu")
		(at 299.903896 -381.41783 -90)
		(property "Reference" "C928"
			(at 0 0 270)
			(layer "F.SilkS")
			(hide yes)
			(effects
				(font
					(size 1.27 1.27)
				)
			)
		)
		(property "Value" ""
			(at 0 0 270)
			(layer "F.Fab")
			(effects
				(font
					(size 1.27 1.27)
				)
			)
		)
		(duplicate_pad_numbers_are_jumpers no)
		(fp_line
			(start -0.299974 0.150114)
			(end -0.299974 -0.150114)
			(stroke
				(width 0.1)
				(type default)
			)
			(layer "F.Fab")
		)
		(fp_line
			(start 0.299974 0.150114)
			(end -0.299974 0.150114)
			(stroke
				(width 0.1)
				(type default)
			)
			(layer "F.Fab")
		)
		(fp_line
			(start -0.299974 -0.150114)
			(end 0.299974 -0.150114)
			(stroke
				(width 0.1)
				(type default)
			)
			(layer "F.Fab")
		)
		(fp_line
			(start 0.299974 -0.150114)
			(end 0.299974 0.150114)
			(stroke
				(width 0.1)
				(type default)
			)
			(layer "F.Fab")
		)
		(pad "1" smd rect
			(at -0.2667 0 270)
			(size 0.3048 0.381)
			(layers "F.Cu" "F.Mask" "F.Paste")
			(net "P5E_CPU0_P0_TX_C_DN<2>")
		)
		(pad "2" smd rect
			(at 0.2667 0 270)
			(size 0.3048 0.381)
			(layers "F.Cu" "F.Mask" "F.Paste")
			(net "P5E_CPU0_P0_TX_DN<2>")
		)
	)
)
